# T6G (Grand Teton) — schematic netlist excerpt (pin names and nets, part order shuffled) for the footprints in the layout excerpt that follows; sources: Cadence DE-HDL packaged netlist, KiCad conversion of 04192023_DAF0TMB3IC0_F0TG_MB_C_brd_V02_OCP.brd

R237  Q_RES  0 5% CHIP  pkg 0402LF  page 82 : A = CPU0_XTRIG_L5 ; B = FM_CPU0_XTRIG_L5
PR254  Q_RES  8.87K 1% EMPTY  pkg 0402LF  page 218 : A = PVDDCR_CPU1_P1_LSET2 ; B = GND

(kicad_pcb
	(version 20260206)
	(generator "pcbnew")
	(generator_version "10.0")
	(general
		(thickness 1.6)
		(legacy_teardrops no)
	)
	(paper "A4")
	(title_block
		(title "04192023_DAF0TMB3IC0_F0TG_MB_C_brd_V02_OCP.brd")
		(comment 1 "Grand Teton / footprints 3856-3857 of 8354")
	)
	(layers
		(0 "F.Cu" signal "TOP")
		(4 "In1.Cu" signal "GND")
		(6 "In2.Cu" signal "IN1")
		(8 "In3.Cu" signal "GND1")
		(10 "In4.Cu" signal "IN2")
		(12 "In5.Cu" signal "GND2")
		(14 "In6.Cu" signal "IN3")
		(16 "In7.Cu" signal "GND3")
		(18 "In8.Cu" signal "VCC")
		(20 "In9.Cu" signal "VCC1")
		(22 "In10.Cu" signal "GND4")
		(24 "In11.Cu" signal "IN4")
		(26 "In12.Cu" signal "GND5")
		(28 "In13.Cu" signal "IN5")
		(30 "In14.Cu" signal "GND6")
		(32 "In15.Cu" signal "IN6")
		(34 "In16.Cu" signal "GND7")
		(2 "B.Cu" signal "BOTTOM")
		(9 "F.Adhes" user "F.Adhesive")
		(11 "B.Adhes" user "B.Adhesive")
		(13 "F.Paste" user "Package Geometry/Pastemask Top")
		(15 "B.Paste" user "Package Geometry/Pastemask Bottom")
		(5 "F.SilkS" user "Ref Des/Silkscreen Top")
		(7 "B.SilkS" user "Ref Des/Silkscreen Bottom")
		(1 "F.Mask" user "Board Geometry/Soldermask Top")
		(3 "B.Mask" user "Board Geometry/Soldermask Bottom")
		(17 "Dwgs.User" user "User.Drawings")
		(19 "Cmts.User" user "User.Comments")
		(21 "Eco1.User" user "User.Eco1")
		(23 "Eco2.User" user "User.Eco2")
		(25 "Edge.Cuts" user "Board Geometry/Outline")
		(27 "Margin" user)
		(31 "F.CrtYd" user "Package Geometry/Place Bound Top")
		(29 "B.CrtYd" user "Package Geometry/Place Bound Bottom")
		(35 "F.Fab" user "Ref Des/Assembly Top")
		(33 "B.Fab" user "Ref Des/Assembly Bottom")
	)
	(footprint ""
		(layer "F.Cu")
		(at 77.460094 -340.204552)
		(property "Reference" "PR254"
			(at 0 0 0)
			(layer "F.SilkS")
			(hide yes)
			(effects
				(font
					(size 1.27 1.27)
				)
			)
		)
		(property "Value" ""
			(at 0 0 0)
			(layer "F.Fab")
			(effects
				(font
					(size 1.27 1.27)
				)
			)
		)
		(duplicate_pad_numbers_are_jumpers no)
		(fp_line
			(start -0.7874 -0.4064)
			(end 0.7874 -0.4064)
			(stroke
				(width 0.1524)
				(type default)
			)
			(layer "F.SilkS")
		)
		(fp_line
			(start -0.7874 0.4064)
			(end -0.7874 -0.4064)
			(stroke
				(width 0.1524)
				(type default)
			)
			(layer "F.SilkS")
		)
		(fp_line
			(start 0.7874 -0.4064)
			(end 0.7874 0.4064)
			(stroke
				(width 0.1524)
				(type default)
			)
			(layer "F.SilkS")
		)
		(fp_line
			(start 0.7874 0.4064)
			(end -0.7874 0.4064)
			(stroke
				(width 0.1524)
				(type default)
			)
			(layer "F.SilkS")
		)
		(fp_line
			(start -0.67945 -0.305054)
			(end -0.12065 -0.305054)
			(stroke
				(width 0.1)
				(type default)
			)
			(layer "F.Fab")
		)
		(fp_line
			(start -0.67945 0.3048)
			(end -0.67945 -0.305054)
			(stroke
				(width 0.1)
				(type default)
			)
			(layer "F.Fab")
		)
		(fp_line
			(start -0.12065 -0.305054)
			(end -0.12065 -0.2794)
			(stroke
				(width 0.1)
				(type default)
			)
			(layer "F.Fab")
		)
		(fp_line
			(start -0.12065 -0.2794)
			(end 0.12065 -0.2794)
			(stroke
				(width 0.1)
				(type default)
			)
			(layer "F.Fab")
		)
		(fp_line
			(start -0.12065 0.2794)
			(end -0.12065 0.3048)
			(stroke
				(width 0.1)
				(type default)
			)
			(layer "F.Fab")
		)
		(fp_line
			(start -0.12065 0.3048)
			(end -0.67945 0.3048)
			(stroke
				(width 0.1)
				(type default)
			)
			(layer "F.Fab")
		)
		(fp_line
			(start 0.120396 0.2794)
			(end -0.12065 0.2794)
			(stroke
				(width 0.1)
				(type default)
			)
			(layer "F.Fab")
		)
		(fp_line
			(start 0.120396 0.3048)
			(end 0.120396 0.2794)
			(stroke
				(width 0.1)
				(type default)
			)
			(layer "F.Fab")
		)
		(fp_line
			(start 0.12065 -0.3048)
			(end 0.67945 -0.3048)
			(stroke
				(width 0.1)
				(type default)
			)
			(layer "F.Fab")
		)
		(fp_line
			(start 0.12065 -0.2794)
			(end 0.12065 -0.3048)
			(stroke
				(width 0.1)
				(type default)
			)
			(layer "F.Fab")
		)
		(fp_line
			(start 0.67945 -0.3048)
			(end 0.67945 0.3048)
			(stroke
				(width 0.1)
				(type default)
			)
			(layer "F.Fab")
		)
		(fp_line
			(start 0.67945 0.3048)
			(end 0.120396 0.3048)
			(stroke
				(width 0.1)
				(type default)
			)
			(layer "F.Fab")
		)
		(pad "1" smd circle
			(at -0.40005 0)
			(size 0 0)
			(layers "F.Cu" "F.Mask" "F.Paste")
			(net "PVDDCR_CPU1_P1_LSET2")
		)
		(pad "2" smd circle
			(at 0.40005 0)
			(size 0 0)
			(layers "F.Cu" "F.Mask" "F.Paste")
			(net "GND")
		)
	)
	(footprint ""
		(layer "F.Cu")
		(at 176.657 -100.294948 90)
		(property "Reference" "R237"
			(at 0 0 90)
			(layer "F.SilkS")
			(hide yes)
			(effects
				(font
					(size 1.27 1.27)
				)
			)
		)
		(property "Value" ""
			(at 0 0 90)
			(layer "F.Fab")
			(effects
				(font
					(size 1.27 1.27)
				)
			)
		)
		(duplicate_pad_numbers_are_jumpers no)
		(fp_line
			(start 0.7874 -0.4064)
			(end 0.7874 0.4064)
			(stroke
				(width 0.1524)
				(type default)
			)
			(layer "F.SilkS")
		)
		(fp_line
			(start -0.7874 -0.4064)
			(end 0.7874 -0.4064)
			(stroke
				(width 0.1524)
				(type default)
			)
			(layer "F.SilkS")
		)
		(fp_line
			(start 0.7874 0.4064)
			(end -0.7874 0.4064)
			(stroke
				(width 0.1524)
				(type default)
			)
			(layer "F.SilkS")
		)
		(fp_line
			(start -0.7874 0.4064)
			(end -0.7874 -0.4064)
			(stroke
				(width 0.1524)
				(type default)
			)
			(layer "F.SilkS")
		)
		(fp_line
			(start -0.12065 -0.305054)
			(end -0.12065 -0.2794)
			(stroke
				(width 0.1)
				(type default)
			)
			(layer "F.Fab")
		)
		(fp_line
			(start -0.67945 -0.305054)
			(end -0.12065 -0.305054)
			(stroke
				(width 0.1)
				(type default)
			)
			(layer "F.Fab")
		)
		(fp_line
			(start 0.67945 -0.3048)
			(end 0.67945 0.3048)
			(stroke
				(width 0.1)
				(type default)
			)
			(layer "F.Fab")
		)
		(fp_line
			(start 0.12065 -0.3048)
			(end 0.67945 -0.3048)
			(stroke
				(width 0.1)
				(type default)
			)
			(layer "F.Fab")
		)
		(fp_line
			(start 0.12065 -0.2794)
			(end 0.12065 -0.3048)
			(stroke
				(width 0.1)
				(type default)
			)
			(layer "F.Fab")
		)
		(fp_line
			(start -0.12065 -0.2794)
			(end 0.12065 -0.2794)
			(stroke
				(width 0.1)
				(type default)
			)
			(layer "F.Fab")
		)
		(fp_line
			(start 0.120396 0.2794)
			(end -0.12065 0.2794)
			(stroke
				(width 0.1)
				(type default)
			)
			(layer "F.Fab")
		)
		(fp_line
			(start -0.12065 0.2794)
			(end -0.12065 0.3048)
			(stroke
				(width 0.1)
				(type default)
			)
			(layer "F.Fab")
		)
		(fp_line
			(start 0.67945 0.3048)
			(end 0.120396 0.3048)
			(stroke
				(width 0.1)
				(type default)
			)
			(layer "F.Fab")
		)
		(fp_line
			(start 0.120396 0.3048)
			(end 0.120396 0.2794)
			(stroke
				(width 0.1)
				(type default)
			)
			(layer "F.Fab")
		)
		(fp_line
			(start -0.12065 0.3048)
			(end -0.67945 0.3048)
			(stroke
				(width 0.1)
				(type default)
			)
			(layer "F.Fab")
		)
		(fp_line
			(start -0.67945 0.3048)
			(end -0.67945 -0.305054)
			(stroke
				(width 0.1)
				(type default)
			)
			(layer "F.Fab")
		)
		(pad "1" smd circle
			(at -0.40005 0 90)
			(size 0 0)
			(layers "F.Cu" "F.Mask" "F.Paste")
			(net "CPU0_XTRIG_L5")
		)
		(pad "2" smd circle
			(at 0.40005 0 90)
			(size 0 0)
			(layers "F.Cu" "F.Mask" "F.Paste")
			(net "FM_CPU0_XTRIG_L5")
		)
	)
)
